# T6G (Grand Teton) — schematic netlist excerpt (pin names and nets, part order shuffled) for the footprints in the layout excerpt that follows; sources: Cadence DE-HDL packaged netlist, KiCad conversion of 04192023_DAF0TMB3IC0_F0TG_MB_C_brd_V02_OCP.brd

PR357  Q_RES  2.2 1% CHIP  pkg 0402LF  page 198 : A = PVDDCR_CPU0_P0_PVCC ; B = PVDDCR_SOC_P0_VCC2
PC410_3  Q_CAP  22UF 16V 20% X6S  pkg C0805  page 219 : A = SW_P12V_AUX_PVDDCR_CPU1_P1_FLT ; B = GND
R6224  Q_RES  33.2 1% EMPTY  pkg 0402LF  page 176 : A = SMB_USB_CPU0_HUB1_SCL ; B = SMB_USB_CPU0_HUB1_SCL_R2

(kicad_pcb
	(version 20260206)
	(generator "pcbnew")
	(generator_version "10.0")
	(general
		(thickness 1.6)
		(legacy_teardrops no)
	)
	(paper "A4")
	(title_block
		(title "04192023_DAF0TMB3IC0_F0TG_MB_C_brd_V02_OCP.brd")
		(comment 1 "Grand Teton / footprints 7418-7420 of 8354")
	)
	(layers
		(0 "F.Cu" signal "TOP")
		(4 "In1.Cu" signal "GND")
		(6 "In2.Cu" signal "IN1")
		(8 "In3.Cu" signal "GND1")
		(10 "In4.Cu" signal "IN2")
		(12 "In5.Cu" signal "GND2")
		(14 "In6.Cu" signal "IN3")
		(16 "In7.Cu" signal "GND3")
		(18 "In8.Cu" signal "VCC")
		(20 "In9.Cu" signal "VCC1")
		(22 "In10.Cu" signal "GND4")
		(24 "In11.Cu" signal "IN4")
		(26 "In12.Cu" signal "GND5")
		(28 "In13.Cu" signal "IN5")
		(30 "In14.Cu" signal "GND6")
		(32 "In15.Cu" signal "IN6")
		(34 "In16.Cu" signal "GND7")
		(2 "B.Cu" signal "BOTTOM")
		(9 "F.Adhes" user "F.Adhesive")
		(11 "B.Adhes" user "B.Adhesive")
		(13 "F.Paste" user "Package Geometry/Pastemask Top")
		(15 "B.Paste" user "Package Geometry/Pastemask Bottom")
		(5 "F.SilkS" user "Ref Des/Silkscreen Top")
		(7 "B.SilkS" user "Ref Des/Silkscreen Bottom")
		(1 "F.Mask" user "Board Geometry/Soldermask Top")
		(3 "B.Mask" user "Board Geometry/Soldermask Bottom")
		(17 "Dwgs.User" user "User.Drawings")
		(19 "Cmts.User" user "User.Comments")
		(21 "Eco1.User" user "User.Eco1")
		(23 "Eco2.User" user "User.Eco2")
		(25 "Edge.Cuts" user "Board Geometry/Outline")
		(27 "Margin" user)
		(31 "F.CrtYd" user "Package Geometry/Place Bound Top")
		(29 "B.CrtYd" user "Package Geometry/Place Bound Bottom")
		(35 "F.Fab" user "Ref Des/Assembly Top")
		(33 "B.Fab" user "Ref Des/Assembly Bottom")
	)
	(footprint ""
		(layer "B.Cu")
		(at 408.45867 -167.53459 90)
		(property "Reference" "PR357"
			(at 0 0 90)
			(layer "B.SilkS")
			(hide yes)
			(effects
				(font
					(size 1.27 1.27)
				)
				(justify mirror)
			)
		)
		(property "Value" ""
			(at 0 0 90)
			(layer "B.Fab")
			(effects
				(font
					(size 1.27 1.27)
				)
				(justify mirror)
			)
		)
		(duplicate_pad_numbers_are_jumpers no)
		(fp_line
			(start 0.7874 -0.4064)
			(end -0.7874 -0.4064)
			(stroke
				(width 0.1524)
				(type default)
			)
			(layer "B.SilkS")
		)
		(fp_line
			(start -0.7874 -0.4064)
			(end -0.7874 0.4064)
			(stroke
				(width 0.1524)
				(type default)
			)
			(layer "B.SilkS")
		)
		(fp_line
			(start 0.7874 0.4064)
			(end 0.7874 -0.4064)
			(stroke
				(width 0.1524)
				(type default)
			)
			(layer "B.SilkS")
		)
		(fp_line
			(start -0.7874 0.4064)
			(end 0.7874 0.4064)
			(stroke
				(width 0.1524)
				(type default)
			)
			(layer "B.SilkS")
		)
		(fp_line
			(start 0.67945 -0.305054)
			(end 0.12065 -0.305054)
			(stroke
				(width 0.1)
				(type default)
			)
			(layer "B.Fab")
		)
		(fp_line
			(start 0.12065 -0.305054)
			(end 0.12065 -0.2794)
			(stroke
				(width 0.1)
				(type default)
			)
			(layer "B.Fab")
		)
		(fp_line
			(start -0.12065 -0.3048)
			(end -0.67945 -0.3048)
			(stroke
				(width 0.1)
				(type default)
			)
			(layer "B.Fab")
		)
		(fp_line
			(start -0.67945 -0.3048)
			(end -0.67945 0.3048)
			(stroke
				(width 0.1)
				(type default)
			)
			(layer "B.Fab")
		)
		(fp_line
			(start 0.12065 -0.2794)
			(end -0.12065 -0.2794)
			(stroke
				(width 0.1)
				(type default)
			)
			(layer "B.Fab")
		)
		(fp_line
			(start -0.12065 -0.2794)
			(end -0.12065 -0.3048)
			(stroke
				(width 0.1)
				(type default)
			)
			(layer "B.Fab")
		)
		(fp_line
			(start 0.12065 0.2794)
			(end 0.12065 0.3048)
			(stroke
				(width 0.1)
				(type default)
			)
			(layer "B.Fab")
		)
		(fp_line
			(start -0.120396 0.2794)
			(end 0.12065 0.2794)
			(stroke
				(width 0.1)
				(type default)
			)
			(layer "B.Fab")
		)
		(fp_line
			(start 0.67945 0.3048)
			(end 0.67945 -0.305054)
			(stroke
				(width 0.1)
				(type default)
			)
			(layer "B.Fab")
		)
		(fp_line
			(start 0.12065 0.3048)
			(end 0.67945 0.3048)
			(stroke
				(width 0.1)
				(type default)
			)
			(layer "B.Fab")
		)
		(fp_line
			(start -0.120396 0.3048)
			(end -0.120396 0.2794)
			(stroke
				(width 0.1)
				(type default)
			)
			(layer "B.Fab")
		)
		(fp_line
			(start -0.67945 0.3048)
			(end -0.120396 0.3048)
			(stroke
				(width 0.1)
				(type default)
			)
			(layer "B.Fab")
		)
		(pad "1" smd circle
			(at 0.40005 0 270)
			(size 0 0)
			(layers "B.Cu" "B.Mask" "B.Paste")
			(net "PVDDCR_CPU0_P0_PVCC")
		)
		(pad "2" smd circle
			(at -0.40005 0 270)
			(size 0 0)
			(layers "B.Cu" "B.Mask" "B.Paste")
			(net "PVDDCR_SOC_P0_VCC2")
		)
	)
	(footprint ""
		(layer "B.Cu")
		(at 71.530718 -338.939632 -90)
		(property "Reference" "PC410_3"
			(at 0 0 90)
			(layer "B.SilkS")
			(hide yes)
			(effects
				(font
					(size 1.27 1.27)
				)
				(justify mirror)
			)
		)
		(property "Value" ""
			(at 0 0 90)
			(layer "B.Fab")
			(effects
				(font
					(size 1.27 1.27)
				)
				(justify mirror)
			)
		)
		(duplicate_pad_numbers_are_jumpers no)
		(fp_line
			(start -1.524 0.762)
			(end 1.524 0.762)
			(stroke
				(width 0.1524)
				(type default)
			)
			(layer "B.SilkS")
		)
		(fp_line
			(start 1.524 0.762)
			(end 1.524 -0.762)
			(stroke
				(width 0.1524)
				(type default)
			)
			(layer "B.SilkS")
		)
		(fp_line
			(start -1.524 -0.762)
			(end -1.524 0.762)
			(stroke
				(width 0.1524)
				(type default)
			)
			(layer "B.SilkS")
		)
		(fp_line
			(start 1.524 -0.762)
			(end -1.524 -0.762)
			(stroke
				(width 0.1524)
				(type default)
			)
			(layer "B.SilkS")
		)
		(fp_line
			(start -1.1049 0.724916)
			(end -1.1049 -0.724916)
			(stroke
				(width 0.1)
				(type default)
			)
			(layer "B.Fab")
		)
		(fp_line
			(start 1.1049 0.724916)
			(end -1.1049 0.724916)
			(stroke
				(width 0.1)
				(type default)
			)
			(layer "B.Fab")
		)
		(fp_line
			(start -1.1049 -0.724916)
			(end 1.1049 -0.724916)
			(stroke
				(width 0.1)
				(type default)
			)
			(layer "B.Fab")
		)
		(fp_line
			(start 1.1049 -0.724916)
			(end 1.1049 0.724916)
			(stroke
				(width 0.1)
				(type default)
			)
			(layer "B.Fab")
		)
		(pad "1" smd rect
			(at 0.889 0 270)
			(size 1.016 1.27)
			(layers "B.Cu" "B.Mask" "B.Paste")
			(net "SW_P12V_AUX_PVDDCR_CPU1_P1_FLT")
		)
		(pad "2" smd rect
			(at -0.889 0 270)
			(size 1.016 1.27)
			(layers "B.Cu" "B.Mask" "B.Paste")
			(net "GND")
		)
	)
	(footprint ""
		(layer "B.Cu")
		(at 111.17834 -62.01791 -90)
		(property "Reference" "R6224"
			(at 0 0 90)
			(layer "B.SilkS")
			(hide yes)
			(effects
				(font
					(size 1.27 1.27)
				)
				(justify mirror)
			)
		)
		(property "Value" ""
			(at 0 0 90)
			(layer "B.Fab")
			(effects
				(font
					(size 1.27 1.27)
				)
				(justify mirror)
			)
		)
		(duplicate_pad_numbers_are_jumpers no)
		(fp_line
			(start -0.7874 0.4064)
			(end 0.7874 0.4064)
			(stroke
				(width 0.1524)
				(type default)
			)
			(layer "B.SilkS")
		)
		(fp_line
			(start 0.7874 0.4064)
			(end 0.7874 -0.4064)
			(stroke
				(width 0.1524)
				(type default)
			)
			(layer "B.SilkS")
		)
		(fp_line
			(start -0.7874 -0.4064)
			(end -0.7874 0.4064)
			(stroke
				(width 0.1524)
				(type default)
			)
			(layer "B.SilkS")
		)
		(fp_line
			(start 0.7874 -0.4064)
			(end -0.7874 -0.4064)
			(stroke
				(width 0.1524)
				(type default)
			)
			(layer "B.SilkS")
		)
		(fp_line
			(start -0.67945 0.3048)
			(end -0.120396 0.3048)
			(stroke
				(width 0.1)
				(type default)
			)
			(layer "B.Fab")
		)
		(fp_line
			(start -0.120396 0.3048)
			(end -0.120396 0.2794)
			(stroke
				(width 0.1)
				(type default)
			)
			(layer "B.Fab")
		)
		(fp_line
			(start 0.12065 0.3048)
			(end 0.67945 0.3048)
			(stroke
				(width 0.1)
				(type default)
			)
			(layer "B.Fab")
		)
		(fp_line
			(start 0.67945 0.3048)
			(end 0.67945 -0.305054)
			(stroke
				(width 0.1)
				(type default)
			)
			(layer "B.Fab")
		)
		(fp_line
			(start -0.120396 0.2794)
			(end 0.12065 0.2794)
			(stroke
				(width 0.1)
				(type default)
			)
			(layer "B.Fab")
		)
		(fp_line
			(start 0.12065 0.2794)
			(end 0.12065 0.3048)
			(stroke
				(width 0.1)
				(type default)
			)
			(layer "B.Fab")
		)
		(fp_line
			(start -0.12065 -0.2794)
			(end -0.12065 -0.3048)
			(stroke
				(width 0.1)
				(type default)
			)
			(layer "B.Fab")
		)
		(fp_line
			(start 0.12065 -0.2794)
			(end -0.12065 -0.2794)
			(stroke
				(width 0.1)
				(type default)
			)
			(layer "B.Fab")
		)
		(fp_line
			(start -0.67945 -0.3048)
			(end -0.67945 0.3048)
			(stroke
				(width 0.1)
				(type default)
			)
			(layer "B.Fab")
		)
		(fp_line
			(start -0.12065 -0.3048)
			(end -0.67945 -0.3048)
			(stroke
				(width 0.1)
				(type default)
			)
			(layer "B.Fab")
		)
		(fp_line
			(start 0.12065 -0.305054)
			(end 0.12065 -0.2794)
			(stroke
				(width 0.1)
				(type default)
			)
			(layer "B.Fab")
		)
		(fp_line
			(start 0.67945 -0.305054)
			(end 0.12065 -0.305054)
			(stroke
				(width 0.1)
				(type default)
			)
			(layer "B.Fab")
		)
		(pad "1" smd circle
			(at 0.40005 0 90)
			(size 0 0)
			(layers "B.Cu" "B.Mask" "B.Paste")
			(net "SMB_USB_CPU0_HUB1_SCL")
		)
		(pad "2" smd circle
			(at -0.40005 0 90)
			(size 0 0)
			(layers "B.Cu" "B.Mask" "B.Paste")
			(net "SMB_USB_CPU0_HUB1_SCL_R2")
		)
	)
)
